(kicad_pcb
	(version 20260206)
	(generator "pcbnew")
	(generator_version "10.0")
	(general
		(thickness 1.6)
		(legacy_teardrops no)
	)
	(paper "A4")
	(title_block
		(title "Bryce Canyon_IOM_IOC_16318-2_OCP.brd")
		(comment 1 "Bryce Canyon / footprint 592 of 1605 (U1), pads 832-896 of 896")
	)
	(layers
		(0 "F.Cu" signal "TOP")
		(4 "In1.Cu" signal "L2GND")
		(6 "In2.Cu" signal "L3")
		(8 "In3.Cu" signal "L4VCC")
		(10 "In4.Cu" signal "L5VCC")
		(12 "In5.Cu" signal "L6")
		(14 "In6.Cu" signal "L7GND")
		(2 "B.Cu" signal "BOTTOM")
		(9 "F.Adhes" user "F.Adhesive")
		(11 "B.Adhes" user "B.Adhesive")
		(13 "F.Paste" user "Package Geometry/Pastemask Top")
		(15 "B.Paste" user "Package Geometry/Pastemask Bottom")
		(5 "F.SilkS" user "Ref Des/Silkscreen Top")
		(7 "B.SilkS" user "Ref Des/Silkscreen Bottom")
		(1 "F.Mask" user "Board Geometry/Soldermask Top")
		(3 "B.Mask" user "Board Geometry/Soldermask Bottom")
		(17 "Dwgs.User" user "User.Drawings")
		(19 "Cmts.User" user "User.Comments")
		(21 "Eco1.User" user "User.Eco1")
		(23 "Eco2.User" user "User.Eco2")
		(25 "Edge.Cuts" user "Board Geometry/Outline")
		(27 "Margin" user)
		(31 "F.CrtYd" user "Package Geometry/Place Bound Top")
		(29 "B.CrtYd" user "Package Geometry/Place Bound Bottom")
		(35 "F.Fab" user "Ref Des/Assembly Top")
		(33 "B.Fab" user "Ref Des/Assembly Bottom")
	)
	(footprint ""
		(layer "F.Cu")
		(at 192.79997 -65.099946 180)
		(property "Reference" "U1"
			(at 0 0 180)
			(layer "F.SilkS")
			(hide yes)
			(effects
				(font
					(size 1.27 1.27)
				)
			)
		)
		(property "Value" "SAS3008C0-1-DB-500020657-1-GP"
			(at -20.374102 -5.0292 180)
			(unlocked yes)
			(layer "F.Fab")
			(hide yes)
			(effects
				(font
					(size 1.016 1.016)
					(thickness 0.1524)
				)
			)
		)
		(property "Device Type" "BGA896D25H78"
			(at -20.374102 -6.5532 180)
			(unlocked yes)
			(layer "F.Fab")
			(hide yes)
			(effects
				(font
					(size 1.016 1.016)
					(thickness 0.1524)
				)
			)
		)
		(duplicate_pad_numbers_are_jumpers no)
		(pad "V26" smd circle
			(at 8.400034 1.999996 180)
			(size 0.3556 0.3556)
			(layers "F.Cu" "F.Mask" "F.Paste")
			(net "P1V8")
		)
		(pad "V27" smd circle
			(at 9.19988 1.999996 180)
			(size 0.3556 0.3556)
			(layers "F.Cu" "F.Mask" "F.Paste")
			(net "GND")
		)
		(pad "V28" smd circle
			(at 9.99998 1.999996 180)
			(size 0.3556 0.3556)
			(layers "F.Cu" "F.Mask" "F.Paste")
			(net "IOC_SCL_2")
		)
		(pad "V29" smd circle
			(at 10.80008 1.999996 180)
			(size 0.3556 0.3556)
			(layers "F.Cu" "F.Mask" "F.Paste")
			(net "IOC_SCL_0")
		)
		(pad "V30" smd circle
			(at 11.599926 1.999996 180)
			(size 0.3556 0.3556)
			(layers "F.Cu" "F.Mask" "F.Paste")
			(net "IOC_SDA_1")
		)
		(pad "W1" smd circle
			(at -11.599926 2.800096 180)
			(size 0.3556 0.3556)
			(layers "F.Cu" "F.Mask" "F.Paste")
			(net "PHY_IOC_TO_CON_B_2_DP_C")
		)
		(pad "W2" smd circle
			(at -10.80008 2.800096 180)
			(size 0.3556 0.3556)
			(layers "F.Cu" "F.Mask" "F.Paste")
			(net "PHY_IOC_TO_CON_B_2_DN_C")
		)
		(pad "W3" smd circle
			(at -9.99998 2.800096 180)
			(size 0.3556 0.3556)
			(layers "F.Cu" "F.Mask" "F.Paste")
			(net "GND")
		)
		(pad "W4" smd circle
			(at -9.19988 2.800096 180)
			(size 0.3556 0.3556)
			(layers "F.Cu" "F.Mask" "F.Paste")
			(net "PHY_CON_B_TO_IOC_2_DP")
		)
		(pad "W5" smd circle
			(at -8.400034 2.800096 180)
			(size 0.3556 0.3556)
			(layers "F.Cu" "F.Mask" "F.Paste")
			(net "PHY_CON_B_TO_IOC_2_DN")
		)
		(pad "W6" smd circle
			(at -7.599934 2.800096 180)
			(size 0.3556 0.3556)
			(layers "F.Cu" "F.Mask" "F.Paste")
			(net "GND")
		)
		(pad "W7" smd circle
			(at -6.800088 2.800096 180)
			(size 0.3556 0.3556)
			(layers "F.Cu" "F.Mask" "F.Paste")
			(net "GND")
		)
		(pad "W8" smd circle
			(at -5.999988 2.800096 180)
			(size 0.3556 0.3556)
			(layers "F.Cu" "F.Mask" "F.Paste")
			(net "GND")
		)
		(pad "W9" smd circle
			(at -5.199888 2.800096 180)
			(size 0.3556 0.3556)
			(layers "F.Cu" "F.Mask" "F.Paste")
			(net "GND")
		)
		(pad "W10" smd circle
			(at -4.400042 2.800096 180)
			(size 0.3556 0.3556)
			(layers "F.Cu" "F.Mask" "F.Paste")
			(net "GND")
		)
		(pad "W11" smd circle
			(at -3.599942 2.800096 180)
			(size 0.3556 0.3556)
			(layers "F.Cu" "F.Mask" "F.Paste")
			(net "GND")
		)
		(pad "W12" smd circle
			(at -2.800096 2.800096 180)
			(size 0.3556 0.3556)
			(layers "F.Cu" "F.Mask" "F.Paste")
			(net "GND")
		)
		(pad "W13" smd circle
			(at -1.999996 2.800096 180)
			(size 0.3556 0.3556)
			(layers "F.Cu" "F.Mask" "F.Paste")
			(net "GND")
		)
		(pad "W14" smd circle
			(at -1.199896 2.800096 180)
			(size 0.3556 0.3556)
			(layers "F.Cu" "F.Mask" "F.Paste")
			(net "P0V975")
		)
		(pad "W15" smd circle
			(at -0.40005 2.800096 180)
			(size 0.3556 0.3556)
			(layers "F.Cu" "F.Mask" "F.Paste")
			(net "GND")
		)
		(pad "W16" smd circle
			(at 0.40005 2.800096 180)
			(size 0.3556 0.3556)
			(layers "F.Cu" "F.Mask" "F.Paste")
			(net "P0V975")
		)
		(pad "W17" smd circle
			(at 1.199896 2.800096 180)
			(size 0.3556 0.3556)
			(layers "F.Cu" "F.Mask" "F.Paste")
			(net "GND")
		)
		(pad "W18" smd circle
			(at 1.999996 2.800096 180)
			(size 0.3556 0.3556)
			(layers "F.Cu" "F.Mask" "F.Paste")
			(net "P0V975")
		)
		(pad "W19" smd circle
			(at 2.800096 2.800096 180)
			(size 0.3556 0.3556)
			(layers "F.Cu" "F.Mask" "F.Paste")
			(net "GND")
		)
		(pad "W20" smd circle
			(at 3.599942 2.800096 180)
			(size 0.3556 0.3556)
			(layers "F.Cu" "F.Mask" "F.Paste")
			(net "P0V975")
		)
		(pad "W21" smd circle
			(at 4.400042 2.800096 180)
			(size 0.3556 0.3556)
			(layers "F.Cu" "F.Mask" "F.Paste")
			(net "GND")
		)
		(pad "W22" smd circle
			(at 5.199888 2.800096 180)
			(size 0.3556 0.3556)
			(layers "F.Cu" "F.Mask" "F.Paste")
			(net "GND")
		)
		(pad "W23" smd circle
			(at 5.999988 2.800096 180)
			(size 0.3556 0.3556)
			(layers "F.Cu" "F.Mask" "F.Paste")
			(net "GND")
		)
		(pad "W24" smd circle
			(at 6.800088 2.800096 180)
			(size 0.3556 0.3556)
			(layers "F.Cu" "F.Mask" "F.Paste")
			(net "GND")
		)
		(pad "W25" smd circle
			(at 7.599934 2.800096 180)
			(size 0.3556 0.3556)
			(layers "F.Cu" "F.Mask" "F.Paste")
			(net "GND")
		)
		(pad "W26" smd circle
			(at 8.400034 2.800096 180)
			(size 0.3556 0.3556)
			(layers "F.Cu" "F.Mask" "F.Paste")
			(net "GND")
		)
		(pad "W27" smd circle
			(at 9.19988 2.800096 180)
			(size 0.3556 0.3556)
			(layers "F.Cu" "F.Mask" "F.Paste")
			(net "P1V8")
		)
		(pad "W28" smd circle
			(at 9.99998 2.800096 180)
			(size 0.3556 0.3556)
			(layers "F.Cu" "F.Mask" "F.Paste")
			(net "IOC_EXT2_LED_B")
		)
		(pad "W29" smd circle
			(at 10.80008 2.800096 180)
			(size 0.3556 0.3556)
			(layers "F.Cu" "F.Mask" "F.Paste")
			(net "IOC_SCL_4")
		)
		(pad "W30" smd circle
			(at 11.599926 2.800096 180)
			(size 0.3556 0.3556)
			(layers "F.Cu" "F.Mask" "F.Paste")
			(net "IOC_GPIO_24")
		)
		(pad "Y1" smd circle
			(at -11.599926 3.599942 180)
			(size 0.3556 0.3556)
			(layers "F.Cu" "F.Mask" "F.Paste")
			(net "SAS0_VDDH")
		)
		(pad "Y2" smd circle
			(at -10.80008 3.599942 180)
			(size 0.3556 0.3556)
			(layers "F.Cu" "F.Mask" "F.Paste")
			(net "GND")
		)
		(pad "Y3" smd circle
			(at -9.99998 3.599942 180)
			(size 0.3556 0.3556)
			(layers "F.Cu" "F.Mask" "F.Paste")
			(net "GND")
		)
		(pad "Y4" smd circle
			(at -9.19988 3.599942 180)
			(size 0.3556 0.3556)
			(layers "F.Cu" "F.Mask" "F.Paste")
			(net "SAS0_AVDD")
		)
		(pad "Y5" smd circle
			(at -8.400034 3.599942 180)
			(size 0.3556 0.3556)
			(layers "F.Cu" "F.Mask" "F.Paste")
			(net "GND")
		)
		(pad "Y6" smd circle
			(at -7.599934 3.599942 180)
			(size 0.3556 0.3556)
			(layers "F.Cu" "F.Mask" "F.Paste")
			(net "SAS0_VDDH")
		)
		(pad "Y7" smd circle
			(at -6.800088 3.599942 180)
			(size 0.3556 0.3556)
			(layers "F.Cu" "F.Mask" "F.Paste")
			(net "SAS0_AVDD")
		)
		(pad "Y8" smd circle
			(at -5.999988 3.599942 180)
			(size 0.3556 0.3556)
			(layers "F.Cu" "F.Mask" "F.Paste")
			(net "GND")
		)
		(pad "Y9" smd circle
			(at -5.199888 3.599942 180)
			(size 0.3556 0.3556)
			(layers "F.Cu" "F.Mask" "F.Paste")
			(net "GND")
		)
		(pad "Y10" smd circle
			(at -4.400042 3.599942 180)
			(size 0.3556 0.3556)
			(layers "F.Cu" "F.Mask" "F.Paste")
			(net "GND")
		)
		(pad "Y11" smd circle
			(at -3.599942 3.599942 180)
			(size 0.3556 0.3556)
			(layers "F.Cu" "F.Mask" "F.Paste")
			(net "GND")
		)
		(pad "Y12" smd circle
			(at -2.800096 3.599942 180)
			(size 0.3556 0.3556)
			(layers "F.Cu" "F.Mask" "F.Paste")
			(net "GND")
		)
		(pad "Y13" smd circle
			(at -1.999996 3.599942 180)
			(size 0.3556 0.3556)
			(layers "F.Cu" "F.Mask" "F.Paste")
			(net "GND")
		)
		(pad "Y14" smd circle
			(at -1.199896 3.599942 180)
			(size 0.3556 0.3556)
			(layers "F.Cu" "F.Mask" "F.Paste")
			(net "GND")
		)
		(pad "Y15" smd circle
			(at -0.40005 3.599942 180)
			(size 0.3556 0.3556)
			(layers "F.Cu" "F.Mask" "F.Paste")
			(net "GND")
		)
		(pad "Y16" smd circle
			(at 0.40005 3.599942 180)
			(size 0.3556 0.3556)
			(layers "F.Cu" "F.Mask" "F.Paste")
			(net "GND")
		)
		(pad "Y17" smd circle
			(at 1.199896 3.599942 180)
			(size 0.3556 0.3556)
			(layers "F.Cu" "F.Mask" "F.Paste")
			(net "P0V975")
		)
		(pad "Y18" smd circle
			(at 1.999996 3.599942 180)
			(size 0.3556 0.3556)
			(layers "F.Cu" "F.Mask" "F.Paste")
			(net "GND")
		)
		(pad "Y19" smd circle
			(at 2.800096 3.599942 180)
			(size 0.3556 0.3556)
			(layers "F.Cu" "F.Mask" "F.Paste")
			(net "P0V975")
		)
		(pad "Y20" smd circle
			(at 3.599942 3.599942 180)
			(size 0.3556 0.3556)
			(layers "F.Cu" "F.Mask" "F.Paste")
			(net "GND")
		)
		(pad "Y21" smd circle
			(at 4.400042 3.599942 180)
			(size 0.3556 0.3556)
			(layers "F.Cu" "F.Mask" "F.Paste")
			(net "P0V975")
		)
		(pad "Y22" smd circle
			(at 5.199888 3.599942 180)
			(size 0.3556 0.3556)
			(layers "F.Cu" "F.Mask" "F.Paste")
			(net "GND")
		)
		(pad "Y23" smd circle
			(at 5.999988 3.599942 180)
			(size 0.3556 0.3556)
			(layers "F.Cu" "F.Mask" "F.Paste")
			(net "GND")
		)
		(pad "Y24" smd circle
			(at 6.800088 3.599942 180)
			(size 0.3556 0.3556)
			(layers "F.Cu" "F.Mask" "F.Paste")
			(net "GND")
		)
		(pad "Y25" smd circle
			(at 7.599934 3.599942 180)
			(size 0.3556 0.3556)
			(layers "F.Cu" "F.Mask" "F.Paste")
			(net "GND")
		)
		(pad "Y26" smd circle
			(at 8.400034 3.599942 180)
			(size 0.3556 0.3556)
			(layers "F.Cu" "F.Mask" "F.Paste")
			(net "P1V8")
		)
		(pad "Y27" smd circle
			(at 9.19988 3.599942 180)
			(size 0.3556 0.3556)
			(layers "F.Cu" "F.Mask" "F.Paste")
			(net "GND")
		)
		(pad "Y28" smd circle
			(at 9.99998 3.599942 180)
			(size 0.3556 0.3556)
			(layers "F.Cu" "F.Mask" "F.Paste")
			(net "IOC_SDA_2")
		)
		(pad "Y29" smd circle
			(at 10.80008 3.599942 180)
			(size 0.3556 0.3556)
			(layers "F.Cu" "F.Mask" "F.Paste")
			(net "SPARE4")
		)
		(pad "Y30" smd circle
			(at 11.599926 3.599942 180)
			(size 0.3556 0.3556)
			(layers "F.Cu" "F.Mask" "F.Paste")
			(net "IOC_GPIO_15")
		)
	)
)
